FILE_TYPE = MACRO_DRAWING;
SET COLOR_WIRE YELLOW;
SET COLOR_PROP MONO;
SET COLOR_DOT WHITE;
SET COLOR_ARC YELLOW;
SET COLOR_BODY GREEN;
SET COLOR_NOTE MONO;
SET PROP_DISPLAY VALUE;
SET PAGE_NUMBER P143;
FORCEADD OFFPAGE..5
(-14350 -1300);
FORCEPROP 2 LAST $XR0 151 
J 0
(-14605 -1300);
DISPLAY 0.638298 (-14605 -1300);
PAINT MONO (-14605 -1300);
FORCEPROP 2 LAST PATH I10
J 0
(-14625 -1250);
DISPLAY 1.021277 (-14625 -1250);
PAINT ORANGE (-14625 -1250);
DISPLAY INVISIBLE (-14625 -1250);
FORCEPROP 2 LAST CDS_LIB mstr_standard
J 0
(-14350 -1300);
PAINT MONO (-14350 -1300);
DISPLAY INVISIBLE (-14350 -1300);
FORCEPROP 1 LAST OFFPAGE TRUE
J 0
(-14025 -1425);
DISPLAY 0.872340 (-14025 -1425);
PAINT GREEN (-14025 -1425);
DISPLAY INVISIBLE (-14025 -1425);
FORCEPROP 1 LAST COMMENT_BODY TRUE
J 0
(-14250 -1375);
DISPLAY 0.872340 (-14250 -1375);
PAINT GREEN (-14250 -1375);
DISPLAY INVISIBLE (-14250 -1375);
FORCEADD OFFPAGE..5
(-14350 -1250);
FORCEPROP 2 LAST $XR0 151 
J 0
(-14605 -1250);
DISPLAY 0.638298 (-14605 -1250);
PAINT MONO (-14605 -1250);
FORCEPROP 2 LAST PATH I11
J 0
(-14625 -1200);
DISPLAY 1.021277 (-14625 -1200);
PAINT ORANGE (-14625 -1200);
DISPLAY INVISIBLE (-14625 -1200);
FORCEPROP 2 LAST CDS_LIB mstr_standard
J 0
(-14350 -1250);
PAINT MONO (-14350 -1250);
DISPLAY INVISIBLE (-14350 -1250);
FORCEPROP 1 LAST OFFPAGE TRUE
J 0
(-14025 -1375);
DISPLAY 0.872340 (-14025 -1375);
PAINT GREEN (-14025 -1375);
DISPLAY INVISIBLE (-14025 -1375);
FORCEPROP 1 LAST COMMENT_BODY TRUE
J 0
(-14250 -1325);
DISPLAY 0.872340 (-14250 -1325);
PAINT GREEN (-14250 -1325);
DISPLAY INVISIBLE (-14250 -1325);
FORCEADD OFFPAGE..5
(-14350 -1200);
FORCEPROP 2 LAST $XR0 151 
J 0
(-14605 -1200);
DISPLAY 0.638298 (-14605 -1200);
PAINT MONO (-14605 -1200);
FORCEPROP 2 LAST PATH I12
J 0
(-14625 -1150);
DISPLAY 1.021277 (-14625 -1150);
PAINT ORANGE (-14625 -1150);
DISPLAY INVISIBLE (-14625 -1150);
FORCEPROP 2 LAST CDS_LIB mstr_standard
J 0
(-14350 -1200);
PAINT MONO (-14350 -1200);
DISPLAY INVISIBLE (-14350 -1200);
FORCEPROP 1 LAST OFFPAGE TRUE
J 0
(-14025 -1325);
DISPLAY 0.872340 (-14025 -1325);
PAINT GREEN (-14025 -1325);
DISPLAY INVISIBLE (-14025 -1325);
FORCEPROP 1 LAST COMMENT_BODY TRUE
J 0
(-14250 -1275);
DISPLAY 0.872340 (-14250 -1275);
PAINT GREEN (-14250 -1275);
DISPLAY INVISIBLE (-14250 -1275);
FORCEADD OFFPAGE..5
(-14350 -1150);
FORCEPROP 2 LAST $XR0 151 
J 0
(-14605 -1150);
DISPLAY 0.638298 (-14605 -1150);
PAINT MONO (-14605 -1150);
FORCEPROP 2 LAST PATH I13
J 0
(-14625 -1100);
DISPLAY 1.021277 (-14625 -1100);
PAINT ORANGE (-14625 -1100);
DISPLAY INVISIBLE (-14625 -1100);
FORCEPROP 2 LAST CDS_LIB mstr_standard
J 0
(-14350 -1150);
PAINT MONO (-14350 -1150);
DISPLAY INVISIBLE (-14350 -1150);
FORCEPROP 1 LAST OFFPAGE TRUE
J 0
(-14025 -1275);
DISPLAY 0.872340 (-14025 -1275);
PAINT GREEN (-14025 -1275);
DISPLAY INVISIBLE (-14025 -1275);
FORCEPROP 1 LAST COMMENT_BODY TRUE
J 0
(-14250 -1225);
DISPLAY 0.872340 (-14250 -1225);
PAINT GREEN (-14250 -1225);
DISPLAY INVISIBLE (-14250 -1225);
FORCEADD OFFPAGE..5
(-14350 -1100);
FORCEPROP 2 LAST $XR0 151 
J 0
(-14605 -1100);
DISPLAY 0.638298 (-14605 -1100);
PAINT MONO (-14605 -1100);
FORCEPROP 2 LAST PATH I14
J 0
(-14625 -1050);
DISPLAY 1.021277 (-14625 -1050);
PAINT ORANGE (-14625 -1050);
DISPLAY INVISIBLE (-14625 -1050);
FORCEPROP 2 LAST CDS_LIB mstr_standard
J 0
(-14350 -1100);
PAINT MONO (-14350 -1100);
DISPLAY INVISIBLE (-14350 -1100);
FORCEPROP 1 LAST OFFPAGE TRUE
J 0
(-14025 -1225);
DISPLAY 0.872340 (-14025 -1225);
PAINT GREEN (-14025 -1225);
DISPLAY INVISIBLE (-14025 -1225);
FORCEPROP 1 LAST COMMENT_BODY TRUE
J 0
(-14250 -1175);
DISPLAY 0.872340 (-14250 -1175);
PAINT GREEN (-14250 -1175);
DISPLAY INVISIBLE (-14250 -1175);
FORCEADD OFFPAGE..5
(-14350 -1050);
FORCEPROP 2 LAST $XR0 151 
J 0
(-14605 -1050);
DISPLAY 0.638298 (-14605 -1050);
PAINT MONO (-14605 -1050);
FORCEPROP 2 LAST CDS_LIB mstr_standard
J 0
(-14350 -1050);
PAINT MONO (-14350 -1050);
DISPLAY INVISIBLE (-14350 -1050);
FORCEPROP 2 LAST PATH I15
J 0
(-14625 -1000);
DISPLAY 1.021277 (-14625 -1000);
PAINT ORANGE (-14625 -1000);
DISPLAY INVISIBLE (-14625 -1000);
FORCEPROP 1 LAST OFFPAGE TRUE
J 0
(-14025 -1175);
DISPLAY 0.872340 (-14025 -1175);
PAINT GREEN (-14025 -1175);
DISPLAY INVISIBLE (-14025 -1175);
FORCEPROP 1 LAST COMMENT_BODY TRUE
J 0
(-14250 -1125);
DISPLAY 0.872340 (-14250 -1125);
PAINT GREEN (-14250 -1125);
DISPLAY INVISIBLE (-14250 -1125);
FORCEADD OFFPAGE..5
(-14350 -1000);
FORCEPROP 2 LAST $XR0 151 
J 0
(-14605 -1000);
DISPLAY 0.638298 (-14605 -1000);
PAINT MONO (-14605 -1000);
FORCEPROP 2 LAST CDS_LIB mstr_standard
J 0
(-14350 -1000);
PAINT MONO (-14350 -1000);
DISPLAY INVISIBLE (-14350 -1000);
FORCEPROP 2 LAST PATH I16
J 0
(-14625 -950);
DISPLAY 1.021277 (-14625 -950);
PAINT ORANGE (-14625 -950);
DISPLAY INVISIBLE (-14625 -950);
FORCEPROP 1 LAST OFFPAGE TRUE
J 0
(-14025 -1125);
DISPLAY 0.872340 (-14025 -1125);
PAINT GREEN (-14025 -1125);
DISPLAY INVISIBLE (-14025 -1125);
FORCEPROP 1 LAST COMMENT_BODY TRUE
J 0
(-14250 -1075);
DISPLAY 0.872340 (-14250 -1075);
PAINT GREEN (-14250 -1075);
DISPLAY INVISIBLE (-14250 -1075);
FORCEADD OFFPAGE..5
(-14350 -950);
FORCEPROP 2 LAST $XR0 151 
J 0
(-14605 -950);
DISPLAY 0.638298 (-14605 -950);
PAINT MONO (-14605 -950);
FORCEPROP 2 LAST PATH I17
J 0
(-14625 -900);
DISPLAY 1.021277 (-14625 -900);
PAINT ORANGE (-14625 -900);
DISPLAY INVISIBLE (-14625 -900);
FORCEPROP 2 LAST CDS_LIB mstr_standard
J 0
(-14350 -950);
PAINT MONO (-14350 -950);
DISPLAY INVISIBLE (-14350 -950);
FORCEPROP 1 LAST OFFPAGE TRUE
J 0
(-14025 -1075);
DISPLAY 0.872340 (-14025 -1075);
PAINT GREEN (-14025 -1075);
DISPLAY INVISIBLE (-14025 -1075);
FORCEPROP 1 LAST COMMENT_BODY TRUE
J 0
(-14250 -1025);
DISPLAY 0.872340 (-14250 -1025);
PAINT GREEN (-14250 -1025);
DISPLAY INVISIBLE (-14250 -1025);
FORCEADD OFFPAGE..5
(-14350 -1800);
FORCEPROP 2 LAST $XR0 151 
J 0
(-14605 -1800);
DISPLAY 0.638298 (-14605 -1800);
PAINT MONO (-14605 -1800);
FORCEPROP 2 LAST CDS_LIB mstr_standard
J 0
(-14350 -1800);
PAINT MONO (-14350 -1800);
DISPLAY INVISIBLE (-14350 -1800);
FORCEPROP 2 LAST PATH I18
J 0
(-14625 -1750);
DISPLAY 1.021277 (-14625 -1750);
PAINT ORANGE (-14625 -1750);
DISPLAY INVISIBLE (-14625 -1750);
FORCEPROP 1 LAST OFFPAGE TRUE
J 0
(-14025 -1925);
DISPLAY 0.872340 (-14025 -1925);
PAINT GREEN (-14025 -1925);
DISPLAY INVISIBLE (-14025 -1925);
FORCEPROP 1 LAST COMMENT_BODY TRUE
J 0
(-14250 -1875);
DISPLAY 0.872340 (-14250 -1875);
PAINT GREEN (-14250 -1875);
DISPLAY INVISIBLE (-14250 -1875);
FORCEADD OFFPAGE..5
(-14350 -1950);
FORCEPROP 2 LAST $XR0 151 
J 0
(-14605 -1950);
DISPLAY 0.638298 (-14605 -1950);
PAINT MONO (-14605 -1950);
FORCEPROP 2 LAST CDS_LIB mstr_standard
J 0
(-14350 -1950);
PAINT MONO (-14350 -1950);
DISPLAY INVISIBLE (-14350 -1950);
FORCEPROP 2 LAST PATH I19
J 0
(-14625 -1900);
DISPLAY 1.021277 (-14625 -1900);
PAINT ORANGE (-14625 -1900);
DISPLAY INVISIBLE (-14625 -1900);
FORCEPROP 1 LAST OFFPAGE TRUE
J 0
(-14025 -2075);
DISPLAY 0.872340 (-14025 -2075);
PAINT GREEN (-14025 -2075);
DISPLAY INVISIBLE (-14025 -2075);
FORCEPROP 1 LAST COMMENT_BODY TRUE
J 0
(-14250 -2025);
DISPLAY 0.872340 (-14250 -2025);
PAINT GREEN (-14250 -2025);
DISPLAY INVISIBLE (-14250 -2025);
FORCEADD OFFPAGE..5
(-14350 -1650);
FORCEPROP 2 LAST $XR0 151 
J 0
(-14605 -1650);
DISPLAY 0.638298 (-14605 -1650);
PAINT MONO (-14605 -1650);
FORCEPROP 2 LAST CDS_LIB mstr_standard
J 0
(-14350 -1650);
PAINT MONO (-14350 -1650);
DISPLAY INVISIBLE (-14350 -1650);
FORCEPROP 2 LAST PATH I2
J 0
(-14625 -1600);
DISPLAY 1.021277 (-14625 -1600);
PAINT ORANGE (-14625 -1600);
DISPLAY INVISIBLE (-14625 -1600);
FORCEPROP 1 LAST OFFPAGE TRUE
J 0
(-14025 -1775);
DISPLAY 0.872340 (-14025 -1775);
PAINT GREEN (-14025 -1775);
DISPLAY INVISIBLE (-14025 -1775);
FORCEPROP 1 LAST COMMENT_BODY TRUE
J 0
(-14250 -1725);
DISPLAY 0.872340 (-14250 -1725);
PAINT GREEN (-14250 -1725);
DISPLAY INVISIBLE (-14250 -1725);
FORCEADD OFFPAGE..5
(-14350 -1850);
FORCEPROP 2 LAST $XR0 151 
J 0
(-14605 -1850);
DISPLAY 0.638298 (-14605 -1850);
PAINT MONO (-14605 -1850);
FORCEPROP 2 LAST CDS_LIB mstr_standard
J 0
(-14350 -1850);
PAINT MONO (-14350 -1850);
DISPLAY INVISIBLE (-14350 -1850);
FORCEPROP 2 LAST PATH I20
J 0
(-14625 -1800);
DISPLAY 1.021277 (-14625 -1800);
PAINT ORANGE (-14625 -1800);
DISPLAY INVISIBLE (-14625 -1800);
FORCEPROP 1 LAST OFFPAGE TRUE
J 0
(-14025 -1975);
DISPLAY 0.872340 (-14025 -1975);
PAINT GREEN (-14025 -1975);
DISPLAY INVISIBLE (-14025 -1975);
FORCEPROP 1 LAST COMMENT_BODY TRUE
J 0
(-14250 -1925);
DISPLAY 0.872340 (-14250 -1925);
PAINT GREEN (-14250 -1925);
DISPLAY INVISIBLE (-14250 -1925);
FORCEADD OFFPAGE..5
(-14350 -2000);
FORCEPROP 2 LAST $XR0 151 
J 0
(-14605 -2000);
DISPLAY 0.638298 (-14605 -2000);
PAINT MONO (-14605 -2000);
FORCEPROP 2 LAST CDS_LIB mstr_standard
J 0
(-14350 -2000);
PAINT MONO (-14350 -2000);
DISPLAY INVISIBLE (-14350 -2000);
FORCEPROP 2 LAST PATH I21
J 0
(-14625 -1950);
DISPLAY 1.021277 (-14625 -1950);
PAINT ORANGE (-14625 -1950);
DISPLAY INVISIBLE (-14625 -1950);
FORCEPROP 1 LAST OFFPAGE TRUE
J 0
(-14025 -2125);
DISPLAY 0.872340 (-14025 -2125);
PAINT GREEN (-14025 -2125);
DISPLAY INVISIBLE (-14025 -2125);
FORCEPROP 1 LAST COMMENT_BODY TRUE
J 0
(-14250 -2075);
DISPLAY 0.872340 (-14250 -2075);
PAINT GREEN (-14250 -2075);
DISPLAY INVISIBLE (-14250 -2075);
FORCEADD OFFPAGE..2
(-11050 -1150);
FORCEPROP 2 LAST $XR0 151 
J 0
(-10861 -1150);
DISPLAY 0.638298 (-10861 -1150);
PAINT MONO (-10861 -1150);
FORCEPROP 2 LAST PATH I23
J 0
(-10850 -1100);
DISPLAY 1.021277 (-10850 -1100);
PAINT ORANGE (-10850 -1100);
DISPLAY INVISIBLE (-10850 -1100);
FORCEPROP 2 LAST CDS_LIB mstr_standard
J 0
(-11050 -1150);
PAINT MONO (-11050 -1150);
DISPLAY INVISIBLE (-11050 -1150);
FORCEPROP 1 LAST OFFPAGE TRUE
J 0
(-10725 -1275);
DISPLAY 0.872340 (-10725 -1275);
PAINT GREEN (-10725 -1275);
DISPLAY INVISIBLE (-10725 -1275);
FORCEPROP 1 LAST COMMENT_BODY TRUE
J 0
(-11095 -1245);
DISPLAY 0.872340 (-11095 -1245);
PAINT GREEN (-11095 -1245);
DISPLAY INVISIBLE (-11095 -1245);
FORCEADD OFFPAGE..2
(-11050 -1200);
FORCEPROP 2 LAST $XR0 151 
J 0
(-10861 -1200);
DISPLAY 0.638298 (-10861 -1200);
PAINT MONO (-10861 -1200);
FORCEPROP 2 LAST PATH I24
J 0
(-10850 -1150);
DISPLAY 1.021277 (-10850 -1150);
PAINT ORANGE (-10850 -1150);
DISPLAY INVISIBLE (-10850 -1150);
FORCEPROP 2 LAST CDS_LIB mstr_standard
J 0
(-11050 -1200);
PAINT MONO (-11050 -1200);
DISPLAY INVISIBLE (-11050 -1200);
FORCEPROP 1 LAST OFFPAGE TRUE
J 0
(-10725 -1325);
DISPLAY 0.872340 (-10725 -1325);
PAINT GREEN (-10725 -1325);
DISPLAY INVISIBLE (-10725 -1325);
FORCEPROP 1 LAST COMMENT_BODY TRUE
J 0
(-11095 -1295);
DISPLAY 0.872340 (-11095 -1295);
PAINT GREEN (-11095 -1295);
DISPLAY INVISIBLE (-11095 -1295);
FORCEADD OFFPAGE..2
(-11050 -1250);
FORCEPROP 2 LAST $XR0 151 
J 0
(-10861 -1250);
DISPLAY 0.638298 (-10861 -1250);
PAINT MONO (-10861 -1250);
FORCEPROP 2 LAST PATH I25
J 0
(-10850 -1200);
DISPLAY 1.021277 (-10850 -1200);
PAINT ORANGE (-10850 -1200);
DISPLAY INVISIBLE (-10850 -1200);
FORCEPROP 2 LAST CDS_LIB mstr_standard
J 0
(-11050 -1250);
PAINT MONO (-11050 -1250);
DISPLAY INVISIBLE (-11050 -1250);
FORCEPROP 1 LAST OFFPAGE TRUE
J 0
(-10725 -1375);
DISPLAY 0.872340 (-10725 -1375);
PAINT GREEN (-10725 -1375);
DISPLAY INVISIBLE (-10725 -1375);
FORCEPROP 1 LAST COMMENT_BODY TRUE
J 0
(-11095 -1345);
DISPLAY 0.872340 (-11095 -1345);
PAINT GREEN (-11095 -1345);
DISPLAY INVISIBLE (-11095 -1345);
FORCEADD OFFPAGE..2
(-11050 -1300);
FORCEPROP 2 LAST $XR0 151 
J 0
(-10861 -1300);
DISPLAY 0.638298 (-10861 -1300);
PAINT MONO (-10861 -1300);
FORCEPROP 2 LAST PATH I26
J 0
(-10850 -1250);
DISPLAY 1.021277 (-10850 -1250);
PAINT ORANGE (-10850 -1250);
DISPLAY INVISIBLE (-10850 -1250);
FORCEPROP 2 LAST CDS_LIB mstr_standard
J 0
(-11050 -1300);
PAINT MONO (-11050 -1300);
DISPLAY INVISIBLE (-11050 -1300);
FORCEPROP 1 LAST OFFPAGE TRUE
J 0
(-10725 -1425);
DISPLAY 0.872340 (-10725 -1425);
PAINT GREEN (-10725 -1425);
DISPLAY INVISIBLE (-10725 -1425);
FORCEPROP 1 LAST COMMENT_BODY TRUE
J 0
(-11095 -1395);
DISPLAY 0.872340 (-11095 -1395);
PAINT GREEN (-11095 -1395);
DISPLAY INVISIBLE (-11095 -1395);
FORCEADD OFFPAGE..2
(-11050 -1350);
FORCEPROP 2 LAST $XR0 151 
J 0
(-10861 -1350);
DISPLAY 0.638298 (-10861 -1350);
PAINT MONO (-10861 -1350);
FORCEPROP 2 LAST PATH I27
J 0
(-10850 -1300);
DISPLAY 1.021277 (-10850 -1300);
PAINT ORANGE (-10850 -1300);
DISPLAY INVISIBLE (-10850 -1300);
FORCEPROP 2 LAST CDS_LIB mstr_standard
J 0
(-11050 -1350);
PAINT MONO (-11050 -1350);
DISPLAY INVISIBLE (-11050 -1350);
FORCEPROP 1 LAST OFFPAGE TRUE
J 0
(-10725 -1475);
DISPLAY 0.872340 (-10725 -1475);
PAINT GREEN (-10725 -1475);
DISPLAY INVISIBLE (-10725 -1475);
FORCEPROP 1 LAST COMMENT_BODY TRUE
J 0
(-11095 -1445);
DISPLAY 0.872340 (-11095 -1445);
PAINT GREEN (-11095 -1445);
DISPLAY INVISIBLE (-11095 -1445);
FORCEADD OFFPAGE..2
(-11050 -1400);
FORCEPROP 2 LAST $XR0 151 
J 0
(-10861 -1400);
DISPLAY 0.638298 (-10861 -1400);
PAINT MONO (-10861 -1400);
FORCEPROP 2 LAST PATH I28
J 0
(-10850 -1350);
DISPLAY 1.021277 (-10850 -1350);
PAINT ORANGE (-10850 -1350);
DISPLAY INVISIBLE (-10850 -1350);
FORCEPROP 2 LAST CDS_LIB mstr_standard
J 0
(-11050 -1400);
PAINT MONO (-11050 -1400);
DISPLAY INVISIBLE (-11050 -1400);
FORCEPROP 1 LAST OFFPAGE TRUE
J 0
(-10725 -1525);
DISPLAY 0.872340 (-10725 -1525);
PAINT GREEN (-10725 -1525);
DISPLAY INVISIBLE (-10725 -1525);
FORCEPROP 1 LAST COMMENT_BODY TRUE
J 0
(-11095 -1495);
DISPLAY 0.872340 (-11095 -1495);
PAINT GREEN (-11095 -1495);
DISPLAY INVISIBLE (-11095 -1495);
FORCEADD OFFPAGE..2
(-11050 -1450);
FORCEPROP 2 LAST $XR0 151 
J 0
(-10861 -1450);
DISPLAY 0.638298 (-10861 -1450);
PAINT MONO (-10861 -1450);
FORCEPROP 2 LAST PATH I29
J 0
(-10850 -1400);
DISPLAY 1.021277 (-10850 -1400);
PAINT ORANGE (-10850 -1400);
DISPLAY INVISIBLE (-10850 -1400);
FORCEPROP 2 LAST CDS_LIB mstr_standard
J 0
(-11050 -1450);
PAINT MONO (-11050 -1450);
DISPLAY INVISIBLE (-11050 -1450);
FORCEPROP 1 LAST OFFPAGE TRUE
J 0
(-10725 -1575);
DISPLAY 0.872340 (-10725 -1575);
PAINT GREEN (-10725 -1575);
DISPLAY INVISIBLE (-10725 -1575);
FORCEPROP 1 LAST COMMENT_BODY TRUE
J 0
(-11095 -1545);
DISPLAY 0.872340 (-11095 -1545);
PAINT GREEN (-11095 -1545);
DISPLAY INVISIBLE (-11095 -1545);
FORCEADD OFFPAGE..5
(-14350 -1600);
FORCEPROP 2 LAST $XR0 151 
J 0
(-14605 -1600);
DISPLAY 0.638298 (-14605 -1600);
PAINT MONO (-14605 -1600);
FORCEPROP 2 LAST CDS_LIB mstr_standard
J 0
(-14350 -1600);
PAINT MONO (-14350 -1600);
DISPLAY INVISIBLE (-14350 -1600);
FORCEPROP 2 LAST PATH I3
J 0
(-14625 -1550);
DISPLAY 1.021277 (-14625 -1550);
PAINT ORANGE (-14625 -1550);
DISPLAY INVISIBLE (-14625 -1550);
FORCEPROP 1 LAST OFFPAGE TRUE
J 0
(-14025 -1725);
DISPLAY 0.872340 (-14025 -1725);
PAINT GREEN (-14025 -1725);
DISPLAY INVISIBLE (-14025 -1725);
FORCEPROP 1 LAST COMMENT_BODY TRUE
J 0
(-14250 -1675);
DISPLAY 0.872340 (-14250 -1675);
PAINT GREEN (-14250 -1675);
DISPLAY INVISIBLE (-14250 -1675);
FORCEADD OFFPAGE..2
(-11050 -1500);
FORCEPROP 2 LAST $XR0 151 
J 0
(-10861 -1500);
DISPLAY 0.638298 (-10861 -1500);
PAINT MONO (-10861 -1500);
FORCEPROP 2 LAST PATH I30
J 0
(-10850 -1450);
DISPLAY 1.021277 (-10850 -1450);
PAINT ORANGE (-10850 -1450);
DISPLAY INVISIBLE (-10850 -1450);
FORCEPROP 2 LAST CDS_LIB mstr_standard
J 0
(-11050 -1500);
PAINT MONO (-11050 -1500);
DISPLAY INVISIBLE (-11050 -1500);
FORCEPROP 1 LAST OFFPAGE TRUE
J 0
(-10725 -1625);
DISPLAY 0.872340 (-10725 -1625);
PAINT GREEN (-10725 -1625);
DISPLAY INVISIBLE (-10725 -1625);
FORCEPROP 1 LAST COMMENT_BODY TRUE
J 0
(-11095 -1595);
DISPLAY 0.872340 (-11095 -1595);
PAINT GREEN (-11095 -1595);
DISPLAY INVISIBLE (-11095 -1595);
FORCEADD OFFPAGE..2
(-11050 -1550);
FORCEPROP 2 LAST $XR0 151 
J 0
(-10861 -1550);
DISPLAY 0.638298 (-10861 -1550);
PAINT MONO (-10861 -1550);
FORCEPROP 2 LAST PATH I31
J 0
(-10850 -1500);
DISPLAY 1.021277 (-10850 -1500);
PAINT ORANGE (-10850 -1500);
DISPLAY INVISIBLE (-10850 -1500);
FORCEPROP 2 LAST CDS_LIB mstr_standard
J 0
(-11050 -1550);
PAINT MONO (-11050 -1550);
DISPLAY INVISIBLE (-11050 -1550);
FORCEPROP 1 LAST OFFPAGE TRUE
J 0
(-10725 -1675);
DISPLAY 0.872340 (-10725 -1675);
PAINT GREEN (-10725 -1675);
DISPLAY INVISIBLE (-10725 -1675);
FORCEPROP 1 LAST COMMENT_BODY TRUE
J 0
(-11095 -1645);
DISPLAY 0.872340 (-11095 -1645);
PAINT GREEN (-11095 -1645);
DISPLAY INVISIBLE (-11095 -1645);
FORCEADD OFFPAGE..2
(-11050 -1650);
FORCEPROP 2 LAST $XR0 151 
J 0
(-10861 -1650);
DISPLAY 0.638298 (-10861 -1650);
PAINT MONO (-10861 -1650);
FORCEPROP 2 LAST CDS_LIB mstr_standard
J 0
(-11050 -1650);
PAINT MONO (-11050 -1650);
DISPLAY INVISIBLE (-11050 -1650);
FORCEPROP 2 LAST PATH I33
J 0
(-10850 -1600);
DISPLAY 1.021277 (-10850 -1600);
PAINT ORANGE (-10850 -1600);
DISPLAY INVISIBLE (-10850 -1600);
FORCEPROP 1 LAST OFFPAGE TRUE
J 0
(-10725 -1775);
DISPLAY 0.872340 (-10725 -1775);
PAINT GREEN (-10725 -1775);
DISPLAY INVISIBLE (-10725 -1775);
FORCEPROP 1 LAST COMMENT_BODY TRUE
J 0
(-11095 -1745);
DISPLAY 0.872340 (-11095 -1745);
PAINT GREEN (-11095 -1745);
DISPLAY INVISIBLE (-11095 -1745);
FORCEADD OFFPAGE..2
(-11050 -1700);
FORCEPROP 2 LAST $XR0 151 
J 0
(-10861 -1700);
DISPLAY 0.638298 (-10861 -1700);
PAINT MONO (-10861 -1700);
FORCEPROP 2 LAST CDS_LIB mstr_standard
J 0
(-11050 -1700);
PAINT MONO (-11050 -1700);
DISPLAY INVISIBLE (-11050 -1700);
FORCEPROP 2 LAST PATH I34
J 0
(-10850 -1650);
DISPLAY 1.021277 (-10850 -1650);
PAINT ORANGE (-10850 -1650);
DISPLAY INVISIBLE (-10850 -1650);
FORCEPROP 1 LAST OFFPAGE TRUE
J 0
(-10725 -1825);
DISPLAY 0.872340 (-10725 -1825);
PAINT GREEN (-10725 -1825);
DISPLAY INVISIBLE (-10725 -1825);
FORCEPROP 1 LAST COMMENT_BODY TRUE
J 0
(-11095 -1795);
DISPLAY 0.872340 (-11095 -1795);
PAINT GREEN (-11095 -1795);
DISPLAY INVISIBLE (-11095 -1795);
FORCEADD OFFPAGE..2
(-11050 -1100);
FORCEPROP 2 LAST $XR0 151 
J 0
(-10861 -1100);
DISPLAY 0.638298 (-10861 -1100);
PAINT MONO (-10861 -1100);
FORCEPROP 2 LAST PATH I36
J 0
(-10850 -1050);
DISPLAY 1.021277 (-10850 -1050);
PAINT ORANGE (-10850 -1050);
DISPLAY INVISIBLE (-10850 -1050);
FORCEPROP 2 LAST CDS_LIB mstr_standard
J 0
(-11050 -1100);
PAINT MONO (-11050 -1100);
DISPLAY INVISIBLE (-11050 -1100);
FORCEPROP 1 LAST OFFPAGE TRUE
J 0
(-10725 -1225);
DISPLAY 0.872340 (-10725 -1225);
PAINT GREEN (-10725 -1225);
DISPLAY INVISIBLE (-10725 -1225);
FORCEPROP 1 LAST COMMENT_BODY TRUE
J 0
(-11095 -1195);
DISPLAY 0.872340 (-11095 -1195);
PAINT GREEN (-11095 -1195);
DISPLAY INVISIBLE (-11095 -1195);
FORCEADD OFFPAGE..2
(-11050 -1050);
FORCEPROP 2 LAST $XR0 151 
J 0
(-10861 -1050);
DISPLAY 0.638298 (-10861 -1050);
PAINT MONO (-10861 -1050);
FORCEPROP 2 LAST CDS_LIB mstr_standard
J 0
(-11050 -1050);
PAINT MONO (-11050 -1050);
DISPLAY INVISIBLE (-11050 -1050);
FORCEPROP 2 LAST PATH I37
J 0
(-10850 -1000);
DISPLAY 1.021277 (-10850 -1000);
PAINT ORANGE (-10850 -1000);
DISPLAY INVISIBLE (-10850 -1000);
FORCEPROP 1 LAST OFFPAGE TRUE
J 0
(-10725 -1175);
DISPLAY 0.872340 (-10725 -1175);
PAINT GREEN (-10725 -1175);
DISPLAY INVISIBLE (-10725 -1175);
FORCEPROP 1 LAST COMMENT_BODY TRUE
J 0
(-11095 -1145);
DISPLAY 0.872340 (-11095 -1145);
PAINT GREEN (-11095 -1145);
DISPLAY INVISIBLE (-11095 -1145);
FORCEADD OFFPAGE..2
(-11050 -1000);
FORCEPROP 2 LAST $XR0 151 
J 0
(-10861 -1000);
DISPLAY 0.638298 (-10861 -1000);
PAINT MONO (-10861 -1000);
FORCEPROP 2 LAST CDS_LIB mstr_standard
J 0
(-11050 -1000);
PAINT MONO (-11050 -1000);
DISPLAY INVISIBLE (-11050 -1000);
FORCEPROP 2 LAST PATH I38
J 0
(-10850 -950);
DISPLAY 1.021277 (-10850 -950);
PAINT ORANGE (-10850 -950);
DISPLAY INVISIBLE (-10850 -950);
FORCEPROP 1 LAST OFFPAGE TRUE
J 0
(-10725 -1125);
DISPLAY 0.872340 (-10725 -1125);
PAINT GREEN (-10725 -1125);
DISPLAY INVISIBLE (-10725 -1125);
FORCEPROP 1 LAST COMMENT_BODY TRUE
J 0
(-11095 -1095);
DISPLAY 0.872340 (-11095 -1095);
PAINT GREEN (-11095 -1095);
DISPLAY INVISIBLE (-11095 -1095);
FORCEADD OFFPAGE..2
(-11050 -1600);
FORCEPROP 2 LAST $XR0 151 
J 0
(-10861 -1600);
DISPLAY 0.638298 (-10861 -1600);
PAINT MONO (-10861 -1600);
FORCEPROP 2 LAST PATH I39
J 0
(-10850 -1550);
DISPLAY 1.021277 (-10850 -1550);
PAINT ORANGE (-10850 -1550);
DISPLAY INVISIBLE (-10850 -1550);
FORCEPROP 2 LAST CDS_LIB mstr_standard
J 0
(-11050 -1600);
PAINT MONO (-11050 -1600);
DISPLAY INVISIBLE (-11050 -1600);
FORCEPROP 1 LAST OFFPAGE TRUE
J 0
(-10725 -1725);
DISPLAY 0.872340 (-10725 -1725);
PAINT GREEN (-10725 -1725);
DISPLAY INVISIBLE (-10725 -1725);
FORCEPROP 1 LAST COMMENT_BODY TRUE
J 0
(-11095 -1695);
DISPLAY 0.872340 (-11095 -1695);
PAINT GREEN (-11095 -1695);
DISPLAY INVISIBLE (-11095 -1695);
FORCEADD OFFPAGE..5
(-14350 -1550);
FORCEPROP 2 LAST $XR0 151 
J 0
(-14605 -1550);
DISPLAY 0.638298 (-14605 -1550);
PAINT MONO (-14605 -1550);
FORCEPROP 2 LAST PATH I4
J 0
(-14625 -1500);
DISPLAY 1.021277 (-14625 -1500);
PAINT ORANGE (-14625 -1500);
DISPLAY INVISIBLE (-14625 -1500);
FORCEPROP 2 LAST CDS_LIB mstr_standard
J 0
(-14350 -1550);
PAINT MONO (-14350 -1550);
DISPLAY INVISIBLE (-14350 -1550);
FORCEPROP 1 LAST OFFPAGE TRUE
J 0
(-14025 -1675);
DISPLAY 0.872340 (-14025 -1675);
PAINT GREEN (-14025 -1675);
DISPLAY INVISIBLE (-14025 -1675);
FORCEPROP 1 LAST COMMENT_BODY TRUE
J 0
(-14250 -1625);
DISPLAY 0.872340 (-14250 -1625);
PAINT GREEN (-14250 -1625);
DISPLAY INVISIBLE (-14250 -1625);
FORCEADD OFFPAGE..2
(-11050 -1900);
FORCEPROP 2 LAST $XR0 151 
J 0
(-10861 -1900);
DISPLAY 0.638298 (-10861 -1900);
PAINT MONO (-10861 -1900);
FORCEPROP 2 LAST CDS_LIB mstr_standard
J 0
(-11050 -1900);
PAINT MONO (-11050 -1900);
DISPLAY INVISIBLE (-11050 -1900);
FORCEPROP 2 LAST PATH I40
J 0
(-10850 -1850);
DISPLAY 1.021277 (-10850 -1850);
PAINT ORANGE (-10850 -1850);
DISPLAY INVISIBLE (-10850 -1850);
FORCEPROP 1 LAST OFFPAGE TRUE
J 0
(-10725 -2025);
DISPLAY 0.872340 (-10725 -2025);
PAINT GREEN (-10725 -2025);
DISPLAY INVISIBLE (-10725 -2025);
FORCEPROP 1 LAST COMMENT_BODY TRUE
J 0
(-11095 -1995);
DISPLAY 0.872340 (-11095 -1995);
PAINT GREEN (-11095 -1995);
DISPLAY INVISIBLE (-11095 -1995);
FORCEADD OFFPAGE..2
(-11050 -1850);
FORCEPROP 2 LAST $XR0 151 
J 0
(-10861 -1850);
DISPLAY 0.638298 (-10861 -1850);
PAINT MONO (-10861 -1850);
FORCEPROP 2 LAST CDS_LIB mstr_standard
J 0
(-11050 -1850);
PAINT MONO (-11050 -1850);
DISPLAY INVISIBLE (-11050 -1850);
FORCEPROP 2 LAST PATH I41
J 0
(-10850 -1800);
DISPLAY 1.021277 (-10850 -1800);
PAINT ORANGE (-10850 -1800);
DISPLAY INVISIBLE (-10850 -1800);
FORCEPROP 1 LAST OFFPAGE TRUE
J 0
(-10725 -1975);
DISPLAY 0.872340 (-10725 -1975);
PAINT GREEN (-10725 -1975);
DISPLAY INVISIBLE (-10725 -1975);
FORCEPROP 1 LAST COMMENT_BODY TRUE
J 0
(-11095 -1945);
DISPLAY 0.872340 (-11095 -1945);
PAINT GREEN (-11095 -1945);
DISPLAY INVISIBLE (-11095 -1945);
FORCEADD OFFPAGE..2
(-11050 -1800);
FORCEPROP 2 LAST $XR0 151 
J 0
(-10861 -1800);
DISPLAY 0.638298 (-10861 -1800);
PAINT MONO (-10861 -1800);
FORCEPROP 2 LAST PATH I42
J 0
(-10850 -1750);
DISPLAY 1.021277 (-10850 -1750);
PAINT ORANGE (-10850 -1750);
DISPLAY INVISIBLE (-10850 -1750);
FORCEPROP 2 LAST CDS_LIB mstr_standard
J 0
(-11050 -1800);
PAINT MONO (-11050 -1800);
DISPLAY INVISIBLE (-11050 -1800);
FORCEPROP 1 LAST OFFPAGE TRUE
J 0
(-10725 -1925);
DISPLAY 0.872340 (-10725 -1925);
PAINT GREEN (-10725 -1925);
DISPLAY INVISIBLE (-10725 -1925);
FORCEPROP 1 LAST COMMENT_BODY TRUE
J 0
(-11095 -1895);
DISPLAY 0.872340 (-11095 -1895);
PAINT GREEN (-11095 -1895);
DISPLAY INVISIBLE (-11095 -1895);
FORCEADD OFFPAGE..2
(-11050 -2050);
FORCEPROP 2 LAST $XR0 151 
J 0
(-10861 -2050);
DISPLAY 0.638298 (-10861 -2050);
PAINT MONO (-10861 -2050);
FORCEPROP 2 LAST CDS_LIB mstr_standard
J 0
(-11050 -2050);
PAINT MONO (-11050 -2050);
DISPLAY INVISIBLE (-11050 -2050);
FORCEPROP 2 LAST PATH I43
J 0
(-10850 -2000);
DISPLAY 1.021277 (-10850 -2000);
PAINT ORANGE (-10850 -2000);
DISPLAY INVISIBLE (-10850 -2000);
FORCEPROP 1 LAST OFFPAGE TRUE
J 0
(-10725 -2175);
DISPLAY 0.872340 (-10725 -2175);
PAINT GREEN (-10725 -2175);
DISPLAY INVISIBLE (-10725 -2175);
FORCEPROP 1 LAST COMMENT_BODY TRUE
J 0
(-11095 -2145);
DISPLAY 0.872340 (-11095 -2145);
PAINT GREEN (-11095 -2145);
DISPLAY INVISIBLE (-11095 -2145);
FORCEADD OFFPAGE..2
(-11050 -2000);
FORCEPROP 2 LAST $XR0 151 
J 0
(-10861 -2000);
DISPLAY 0.638298 (-10861 -2000);
PAINT MONO (-10861 -2000);
FORCEPROP 2 LAST PATH I44
J 0
(-10850 -1950);
DISPLAY 1.021277 (-10850 -1950);
PAINT ORANGE (-10850 -1950);
DISPLAY INVISIBLE (-10850 -1950);
FORCEPROP 2 LAST CDS_LIB mstr_standard
J 0
(-11050 -2000);
PAINT MONO (-11050 -2000);
DISPLAY INVISIBLE (-11050 -2000);
FORCEPROP 1 LAST OFFPAGE TRUE
J 0
(-10725 -2125);
DISPLAY 0.872340 (-10725 -2125);
PAINT GREEN (-10725 -2125);
DISPLAY INVISIBLE (-10725 -2125);
FORCEPROP 1 LAST COMMENT_BODY TRUE
J 0
(-11095 -2095);
DISPLAY 0.872340 (-11095 -2095);
PAINT GREEN (-11095 -2095);
DISPLAY INVISIBLE (-11095 -2095);
FORCEADD OFFPAGE..2
(-11050 -2550);
FORCEPROP 2 LAST $XR0 151 
J 0
(-10861 -2550);
DISPLAY 0.638298 (-10861 -2550);
PAINT MONO (-10861 -2550);
FORCEPROP 2 LAST PATH I45
J 0
(-10525 -2500);
DISPLAY 1.021277 (-10525 -2500);
PAINT ORANGE (-10525 -2500);
DISPLAY INVISIBLE (-10525 -2500);
FORCEPROP 2 LAST CDS_LIB mstr_standard
J 0
(-11050 -2550);
PAINT MONO (-11050 -2550);
DISPLAY INVISIBLE (-11050 -2550);
FORCEPROP 1 LAST OFFPAGE TRUE
J 0
(-10725 -2675);
DISPLAY 0.872340 (-10725 -2675);
PAINT GREEN (-10725 -2675);
DISPLAY INVISIBLE (-10725 -2675);
FORCEPROP 1 LAST COMMENT_BODY TRUE
J 0
(-11095 -2645);
DISPLAY 0.872340 (-11095 -2645);
PAINT GREEN (-11095 -2645);
DISPLAY INVISIBLE (-11095 -2645);
FORCEADD OFFPAGE..2
(-11050 -2600);
FORCEPROP 2 LAST $XR0 151 
J 0
(-10861 -2600);
DISPLAY 0.638298 (-10861 -2600);
PAINT MONO (-10861 -2600);
FORCEPROP 2 LAST PATH I46
J 0
(-10850 -2550);
DISPLAY 1.021277 (-10850 -2550);
PAINT ORANGE (-10850 -2550);
DISPLAY INVISIBLE (-10850 -2550);
FORCEPROP 2 LAST CDS_LIB mstr_standard
J 0
(-11050 -2600);
PAINT MONO (-11050 -2600);
DISPLAY INVISIBLE (-11050 -2600);
FORCEPROP 1 LAST OFFPAGE TRUE
J 0
(-10725 -2725);
DISPLAY 0.872340 (-10725 -2725);
PAINT GREEN (-10725 -2725);
DISPLAY INVISIBLE (-10725 -2725);
FORCEPROP 1 LAST COMMENT_BODY TRUE
J 0
(-11095 -2695);
DISPLAY 0.872340 (-11095 -2695);
PAINT GREEN (-11095 -2695);
DISPLAY INVISIBLE (-11095 -2695);
FORCEADD OFFPAGE..2
(-11050 -2700);
FORCEPROP 2 LAST $XR0 151 
J 0
(-10861 -2700);
DISPLAY 0.638298 (-10861 -2700);
PAINT MONO (-10861 -2700);
FORCEPROP 2 LAST CDS_LIB mstr_standard
J 0
(-11050 -2700);
PAINT MONO (-11050 -2700);
DISPLAY INVISIBLE (-11050 -2700);
FORCEPROP 2 LAST PATH I47
J 0
(-10850 -2650);
DISPLAY 1.021277 (-10850 -2650);
PAINT ORANGE (-10850 -2650);
DISPLAY INVISIBLE (-10850 -2650);
FORCEPROP 1 LAST OFFPAGE TRUE
J 0
(-10725 -2825);
DISPLAY 0.872340 (-10725 -2825);
PAINT GREEN (-10725 -2825);
DISPLAY INVISIBLE (-10725 -2825);
FORCEPROP 1 LAST COMMENT_BODY TRUE
J 0
(-11095 -2795);
DISPLAY 0.872340 (-11095 -2795);
PAINT GREEN (-11095 -2795);
DISPLAY INVISIBLE (-11095 -2795);
FORCEADD OFFPAGE..2
(-11050 -2750);
FORCEPROP 2 LAST $XR0 151 
J 0
(-10861 -2750);
DISPLAY 0.638298 (-10861 -2750);
PAINT MONO (-10861 -2750);
FORCEPROP 2 LAST PATH I48
J 0
(-10850 -2700);
DISPLAY 1.021277 (-10850 -2700);
PAINT ORANGE (-10850 -2700);
DISPLAY INVISIBLE (-10850 -2700);
FORCEPROP 2 LAST CDS_LIB mstr_standard
J 0
(-11050 -2750);
PAINT MONO (-11050 -2750);
DISPLAY INVISIBLE (-11050 -2750);
FORCEPROP 1 LAST OFFPAGE TRUE
J 0
(-10725 -2875);
DISPLAY 0.872340 (-10725 -2875);
PAINT GREEN (-10725 -2875);
DISPLAY INVISIBLE (-10725 -2875);
FORCEPROP 1 LAST COMMENT_BODY TRUE
J 0
(-11095 -2845);
DISPLAY 0.872340 (-11095 -2845);
PAINT GREEN (-11095 -2845);
DISPLAY INVISIBLE (-11095 -2845);
FORCEADD OFFPAGE..2
(-11050 -2350);
FORCEPROP 2 LAST $XR0 151 
J 0
(-10861 -2350);
DISPLAY 0.638298 (-10861 -2350);
PAINT MONO (-10861 -2350);
FORCEPROP 2 LAST PATH I49
J 0
(-10850 -2300);
DISPLAY 1.021277 (-10850 -2300);
PAINT ORANGE (-10850 -2300);
DISPLAY INVISIBLE (-10850 -2300);
FORCEPROP 2 LAST CDS_LIB mstr_standard
J 0
(-11050 -2350);
PAINT MONO (-11050 -2350);
DISPLAY INVISIBLE (-11050 -2350);
FORCEPROP 1 LAST OFFPAGE TRUE
J 0
(-10725 -2475);
DISPLAY 0.872340 (-10725 -2475);
PAINT GREEN (-10725 -2475);
DISPLAY INVISIBLE (-10725 -2475);
FORCEPROP 1 LAST COMMENT_BODY TRUE
J 0
(-11095 -2445);
DISPLAY 0.872340 (-11095 -2445);
PAINT GREEN (-11095 -2445);
DISPLAY INVISIBLE (-11095 -2445);
FORCEADD OFFPAGE..5
(-14350 -1500);
FORCEPROP 2 LAST $XR0 151 
J 0
(-14605 -1500);
DISPLAY 0.638298 (-14605 -1500);
PAINT MONO (-14605 -1500);
FORCEPROP 2 LAST PATH I5
J 0
(-14625 -1450);
DISPLAY 1.021277 (-14625 -1450);
PAINT ORANGE (-14625 -1450);
DISPLAY INVISIBLE (-14625 -1450);
FORCEPROP 2 LAST CDS_LIB mstr_standard
J 0
(-14350 -1500);
PAINT MONO (-14350 -1500);
DISPLAY INVISIBLE (-14350 -1500);
FORCEPROP 1 LAST OFFPAGE TRUE
J 0
(-14025 -1625);
DISPLAY 0.872340 (-14025 -1625);
PAINT GREEN (-14025 -1625);
DISPLAY INVISIBLE (-14025 -1625);
FORCEPROP 1 LAST COMMENT_BODY TRUE
J 0
(-14250 -1575);
DISPLAY 0.872340 (-14250 -1575);
PAINT GREEN (-14250 -1575);
DISPLAY INVISIBLE (-14250 -1575);
FORCEADD OFFPAGE..2
(-11050 -2300);
FORCEPROP 2 LAST $XR0 151 
J 0
(-10861 -2300);
DISPLAY 0.638298 (-10861 -2300);
PAINT MONO (-10861 -2300);
FORCEPROP 2 LAST PATH I50
J 0
(-10850 -2250);
DISPLAY 1.021277 (-10850 -2250);
PAINT ORANGE (-10850 -2250);
DISPLAY INVISIBLE (-10850 -2250);
FORCEPROP 2 LAST CDS_LIB mstr_standard
J 0
(-11050 -2300);
PAINT MONO (-11050 -2300);
DISPLAY INVISIBLE (-11050 -2300);
FORCEPROP 1 LAST OFFPAGE TRUE
J 0
(-10725 -2425);
DISPLAY 0.872340 (-10725 -2425);
PAINT GREEN (-10725 -2425);
DISPLAY INVISIBLE (-10725 -2425);
FORCEPROP 1 LAST COMMENT_BODY TRUE
J 0
(-11095 -2395);
DISPLAY 0.872340 (-11095 -2395);
PAINT GREEN (-11095 -2395);
DISPLAY INVISIBLE (-11095 -2395);
FORCEADD OFFPAGE..2
(-11050 -2400);
FORCEPROP 2 LAST $XR0 151 
J 0
(-10861 -2400);
DISPLAY 0.638298 (-10861 -2400);
PAINT MONO (-10861 -2400);
FORCEPROP 2 LAST PATH I51
J 0
(-10850 -2350);
DISPLAY 1.021277 (-10850 -2350);
PAINT ORANGE (-10850 -2350);
DISPLAY INVISIBLE (-10850 -2350);
FORCEPROP 2 LAST CDS_LIB mstr_standard
J 0
(-11050 -2400);
PAINT MONO (-11050 -2400);
DISPLAY INVISIBLE (-11050 -2400);
FORCEPROP 1 LAST OFFPAGE TRUE
J 0
(-10725 -2525);
DISPLAY 0.872340 (-10725 -2525);
PAINT GREEN (-10725 -2525);
DISPLAY INVISIBLE (-10725 -2525);
FORCEPROP 1 LAST COMMENT_BODY TRUE
J 0
(-11095 -2495);
DISPLAY 0.872340 (-11095 -2495);
PAINT GREEN (-11095 -2495);
DISPLAY INVISIBLE (-11095 -2495);
FORCEADD OFFPAGE..2
(-11050 -2450);
FORCEPROP 2 LAST $XR0 151 
J 0
(-10861 -2450);
DISPLAY 0.638298 (-10861 -2450);
PAINT MONO (-10861 -2450);
FORCEPROP 2 LAST PATH I52
J 0
(-10850 -2400);
DISPLAY 1.021277 (-10850 -2400);
PAINT ORANGE (-10850 -2400);
DISPLAY INVISIBLE (-10850 -2400);
FORCEPROP 2 LAST CDS_LIB mstr_standard
J 0
(-11050 -2450);
PAINT MONO (-11050 -2450);
DISPLAY INVISIBLE (-11050 -2450);
FORCEPROP 1 LAST OFFPAGE TRUE
J 0
(-10725 -2575);
DISPLAY 0.872340 (-10725 -2575);
PAINT GREEN (-10725 -2575);
DISPLAY INVISIBLE (-10725 -2575);
FORCEPROP 1 LAST COMMENT_BODY TRUE
J 0
(-11095 -2545);
DISPLAY 0.872340 (-11095 -2545);
PAINT GREEN (-11095 -2545);
DISPLAY INVISIBLE (-11095 -2545);
FORCEADD GND..1
R 1
(-10250 -2150);
FORCEPROP 3 LASTPIN (-10300 -2150) SIG_NAME GND\g
J 0
(-10290 -2140);
DISPLAY 0.659574 (-10290 -2140);
PAINT MONO (-10290 -2140);
DISPLAY INVISIBLE (-10290 -2140);
FORCEPROP 1 LAST PATH I57
R 1
J 0
(-10250 -2075);
DISPLAY 0.872340 (-10250 -2075);
PAINT AQUA (-10250 -2075);
DISPLAY INVISIBLE (-10250 -2075);
FORCEPROP 2 LAST CDS_LIB mstr_symbols
R 1
J 0
(-10250 -2150);
PAINT MONO (-10250 -2150);
DISPLAY INVISIBLE (-10250 -2150);
FORCEPROP 1 LAST SIZE 1B
R 1
J 0
(-10200 -2075);
DISPLAY 0.872340 (-10200 -2075);
PAINT AQUA (-10200 -2075);
DISPLAY INVISIBLE (-10200 -2075);
FORCEPROP 1 LAST VOLTAGE 0.0V
R 1
J 0
(-10207 -2195);
DISPLAY 0.340426 (-10207 -2195);
PAINT GREEN (-10207 -2195);
DISPLAY INVISIBLE (-10207 -2195);
FORCEPROP 1 LAST BODY_TYPE PLUMBING
R 1
J 0
(-10207 -2195);
DISPLAY 0.340426 (-10207 -2195);
PAINT GREEN (-10207 -2195);
DISPLAY INVISIBLE (-10207 -2195);
FORCEPROP 1 LAST HDL_POWER GND
R 1
J 0
(-10400 -2150);
DISPLAY 0.872340 (-10400 -2150);
PAINT GREEN (-10400 -2150);
DISPLAY INVISIBLE (-10400 -2150);
FORCEADD RES..2
R 7
(-11000 -2150);
FORCEPROP 1 LASTPIN (-11100 -2150) $PN 2
J 0
(-11128 -2132);
DISPLAY 0.787234 (-11128 -2132);
PAINT ORANGE (-11128 -2132);
FORCEPROP 1 LAST LOCATION R1T27
J 0
(-11321 -2134);
DISPLAY 0.617021 (-11321 -2134);
PAINT AQUA (-11321 -2134);
FORCEPROP 1 LASTPIN (-10900 -2150) $PN 1
J 0
(-10901 -2132);
DISPLAY 0.787234 (-10901 -2132);
PAINT ORANGE (-10901 -2132);
FORCEPROP 1 LAST VALUE 240
J 0
(-10846 -2134);
DISPLAY 0.617021 (-10846 -2134);
PAINT SKYBLUE (-10846 -2134);
FORCEPROP 1 LAST TOLERANCE 1.0%
J 0
(-10721 -2134);
DISPLAY 0.617021 (-10721 -2134);
PAINT SKYBLUE (-10721 -2134);
FORCEPROP 1 LAST MATERIAL CHIP
J 0
(-10696 -2039);
DISPLAY 0.617021 (-10696 -2039);
PAINT SKYBLUE (-10696 -2039);
FORCEPROP 1 LAST WATTAGE 1/16W
J 0
(-10696 -1989);
DISPLAY 0.617021 (-10696 -1989);
PAINT SKYBLUE (-10696 -1989);
FORCEPROP 1 LAST PART_NUMBER G21796-294
J 0
(-10696 -2089);
DISPLAY 0.617021 (-10696 -2089);
PAINT BLUE (-10696 -2089);
FORCEPROP 1 LAST PACK_TYPE 0402
J 0
(-10596 -2139);
DISPLAY 0.617021 (-10596 -2139);
PAINT SKYBLUE (-10596 -2139);
FORCEPROP 2 LAST SEC_TYPE 0402
J 0
(-10625 -2100);
DISPLAY 1.021277 (-10625 -2100);
PAINT ORANGE (-10625 -2100);
DISPLAY INVISIBLE (-10625 -2100);
FORCEPROP 0 LAST SEC 1
J 0
(-10625 -2100);
DISPLAY 0.680851 (-10625 -2100);
PAINT MONO (-10625 -2100);
DISPLAY INVISIBLE (-10625 -2100);
FORCEPROP 2 LAST ROOM BMC_MEMORY
R 1
J 0
(-10777 -2148);
DISPLAY 1.021277 (-10777 -2148);
PAINT ORANGE (-10777 -2148);
DISPLAY INVISIBLE (-10777 -2148);
FORCEPROP 2 LAST BOM_COST SM_MEM
R 1
J 0
(-10727 -2148);
DISPLAY 1.021277 (-10727 -2148);
PAINT ORANGE (-10727 -2148);
DISPLAY INVISIBLE (-10727 -2148);
FORCEPROP 2 LAST CDS_LIB mstr_discrete
R 1
J 0
(-10953 -2197);
PAINT MONO (-10953 -2197);
DISPLAY INVISIBLE (-10953 -2197);
FORCEPROP 1 LAST PATH I58
R 1
J 0
(-10779 -2146);
DISPLAY 0.978723 (-10779 -2146);
PAINT WHITE (-10779 -2146);
DISPLAY INVISIBLE (-10779 -2146);
FORCEADD OFFPAGE..5
(-14350 -1450);
FORCEPROP 2 LAST $XR0 151 
J 0
(-14605 -1450);
DISPLAY 0.638298 (-14605 -1450);
PAINT MONO (-14605 -1450);
FORCEPROP 2 LAST PATH I6
J 0
(-14625 -1400);
DISPLAY 1.021277 (-14625 -1400);
PAINT ORANGE (-14625 -1400);
DISPLAY INVISIBLE (-14625 -1400);
FORCEPROP 2 LAST CDS_LIB mstr_standard
J 0
(-14350 -1450);
PAINT MONO (-14350 -1450);
DISPLAY INVISIBLE (-14350 -1450);
FORCEPROP 1 LAST OFFPAGE TRUE
J 0
(-14025 -1575);
DISPLAY 0.872340 (-14025 -1575);
PAINT GREEN (-14025 -1575);
DISPLAY INVISIBLE (-14025 -1575);
FORCEPROP 1 LAST COMMENT_BODY TRUE
J 0
(-14250 -1525);
DISPLAY 0.872340 (-14250 -1525);
PAINT GREEN (-14250 -1525);
DISPLAY INVISIBLE (-14250 -1525);
FORCEADD AST2520A1-GP-GP..1
(-12850 -1850);
FORCEPROP 1 LAST VALUE AST2520A1-GP-GP
J 0
(-13425 -2950);
DISPLAY 0.617021 (-13425 -2950);
PAINT GREEN (-13425 -2950);
FORCEPROP 1 LAST LOCATION U25W4
J 0
(-13425 -775);
DISPLAY 0.617021 (-13425 -775);
PAINT GREEN (-13425 -775);
FORCEPROP 2 LAST CDS_LIB w_hdl
J 0
(-12850 -1850);
PAINT MONO (-12850 -1850);
DISPLAY INVISIBLE (-12850 -1850);
FORCEPROP 1 LAST CDS_LMAN_SYM_OUTLINE -575,1050,575,-1050
J 0
(-12850 -1850);
DISPLAY 0.468085 (-12850 -1850);
PAINT GREEN (-12850 -1850);
DISPLAY INVISIBLE (-12850 -1850);
FORCEPROP 1 LAST PATH I63
J 0
(-12850 -1850);
DISPLAY 0.617021 (-12850 -1850);
PAINT GREEN (-12850 -1850);
DISPLAY INVISIBLE (-12850 -1850);
FORCEPROP 1 LAST PACK_TYPE ASIC2-GB1
J 0
(-12850 -1850);
DISPLAY 0.617021 (-12850 -1850);
PAINT GREEN (-12850 -1850);
DISPLAY INVISIBLE (-12850 -1850);
FORCEPROP 1 LAST PART_NUMBER 071.2520A.M001
J 0
(-12850 -1850);
DISPLAY 0.617021 (-12850 -1850);
PAINT GREEN (-12850 -1850);
DISPLAY INVISIBLE (-12850 -1850);
FORCEADD OFFPAGE..4
(-10250 -2200);
FORCEPROP 2 LAST $XR0 151 
J 0
(-10064 -2200);
DISPLAY 0.638298 (-10064 -2200);
PAINT MONO (-10064 -2200);
FORCEPROP 1 LAST OFFPAGE TRUE
J 0
(-9925 -2325);
DISPLAY 0.872340 (-9925 -2325);
PAINT GREEN (-9925 -2325);
DISPLAY INVISIBLE (-9925 -2325);
FORCEPROP 1 LAST COMMENT_BODY TRUE
J 0
(-10275 -2300);
DISPLAY 0.872340 (-10275 -2300);
PAINT GREEN (-10275 -2300);
DISPLAY INVISIBLE (-10275 -2300);
FORCEPROP 2 LAST PATH I64
J 0
(-10075 -2125);
DISPLAY 1.021277 (-10075 -2125);
PAINT ORANGE (-10075 -2125);
DISPLAY INVISIBLE (-10075 -2125);
FORCEPROP 2 LAST CDS_LIB mstr_standard
J 0
(-10250 -2200);
PAINT MONO (-10250 -2200);
DISPLAY INVISIBLE (-10250 -2200);
FORCEADD GND..1
R 2
(-10550 -2650);
FORCEPROP 3 LASTPIN (-10550 -2600) SIG_NAME GND\g
J 0
(-10540 -2590);
DISPLAY 0.659574 (-10540 -2590);
PAINT MONO (-10540 -2590);
DISPLAY INVISIBLE (-10540 -2590);
FORCEPROP 1 LAST VOLTAGE 0.0V
J 2
(-10489 -2677);
DISPLAY 0.340426 (-10489 -2677);
PAINT GREEN (-10489 -2677);
DISPLAY INVISIBLE (-10489 -2677);
FORCEPROP 1 LAST SIZE 1B
J 2
(-10584 -2659);
DISPLAY 0.872340 (-10584 -2659);
PAINT AQUA (-10584 -2659);
DISPLAY INVISIBLE (-10584 -2659);
FORCEPROP 2 LAST CDS_LIB mstr_symbols
R 3
J 2
(-10503 -2603);
PAINT MONO (-10503 -2603);
DISPLAY INVISIBLE (-10503 -2603);
FORCEPROP 1 LAST BODY_TYPE PLUMBING
J 2
(-10489 -2677);
DISPLAY 0.340426 (-10489 -2677);
PAINT GREEN (-10489 -2677);
DISPLAY INVISIBLE (-10489 -2677);
FORCEPROP 1 LAST HDL_POWER GND
J 2
(-10509 -2459);
DISPLAY 0.872340 (-10509 -2459);
PAINT GREEN (-10509 -2459);
DISPLAY INVISIBLE (-10509 -2459);
FORCEPROP 1 LAST PATH I65
J 2
(-10584 -2609);
DISPLAY 0.872340 (-10584 -2609);
PAINT AQUA (-10584 -2609);
DISPLAY INVISIBLE (-10584 -2609);
FORCEADD CAP_A..1
(-10550 -2450);
FORCEPROP 1 LAST PART_NUMBER A36096-030
J 0
(-10500 -2600);
DISPLAY 0.617021 (-10500 -2600);
PAINT BLUE (-10500 -2600);
FORCEPROP 1 LASTPIN (-10550 -2550) $PN 2
J 0
(-10540 -2570);
DISPLAY 0.617021 (-10540 -2570);
PAINT ORANGE (-10540 -2570);
FORCEPROP 1 LASTPIN (-10550 -2350) $PN 1
J 0
(-10540 -2370);
DISPLAY 0.617021 (-10540 -2370);
PAINT ORANGE (-10540 -2370);
FORCEPROP 1 LAST PACK_TYPE 0402V
J 0
(-10500 -2650);
DISPLAY 0.617021 (-10500 -2650);
PAINT SKYBLUE (-10500 -2650);
FORCEPROP 1 LAST MATERIAL X7R
J 0
(-10500 -2550);
DISPLAY 0.617021 (-10500 -2550);
PAINT SKYBLUE (-10500 -2550);
FORCEPROP 1 LAST LOCATION C25W22
J 0
(-10500 -2350);
DISPLAY 0.617021 (-10500 -2350);
PAINT AQUA (-10500 -2350);
FORCEPROP 1 LAST VALUE 0.1UF
J 0
(-10500 -2400);
DISPLAY 0.617021 (-10500 -2400);
PAINT SKYBLUE (-10500 -2400);
FORCEPROP 1 LAST VOLTAGE 16V
J 0
(-10500 -2450);
DISPLAY 0.617021 (-10500 -2450);
PAINT SKYBLUE (-10500 -2450);
FORCEPROP 1 LAST TOLERANCE 10%
J 0
(-10500 -2500);
DISPLAY 0.617021 (-10500 -2500);
PAINT SKYBLUE (-10500 -2500);
FORCEPROP 1 LAST PATH I67
J 0
(-10500 -2300);
DISPLAY 0.978723 (-10500 -2300);
PAINT WHITE (-10500 -2300);
DISPLAY INVISIBLE (-10500 -2300);
FORCEPROP 2 LAST CDS_LIB dev_discrete
J 0
(-10550 -2450);
PAINT ORANGE (-10550 -2450);
DISPLAY INVISIBLE (-10550 -2450);
FORCEPROP 2 LAST CDS_SEC 1
J 0
(-10500 -2300);
PAINT ORANGE (-10500 -2300);
DISPLAY INVISIBLE (-10500 -2300);
FORCEPROP 2 LAST ROOM VDDQ_KLM_PWR_VR
J 0
(-10500 -2300);
DISPLAY 1.361702 (-10500 -2300);
PAINT ORANGE (-10500 -2300);
DISPLAY INVISIBLE (-10500 -2300);
FORCEPROP 2 LAST SEC_TYPE 0402V
J 0
(-10500 -2225);
DISPLAY 1.021277 (-10500 -2225);
PAINT ORANGE (-10500 -2225);
DISPLAY INVISIBLE (-10500 -2225);
FORCEPROP 2 LAST SEC 1
J 0
(-10500 -2225);
DISPLAY 0.680851 (-10500 -2225);
PAINT MONO (-10500 -2225);
DISPLAY INVISIBLE (-10500 -2225);
FORCEPROP 2 LAST CDS_LOCATION C25W22
J 0
(-10500 -2350);
DISPLAY 0.617021 (-10500 -2350);
PAINT AQUA (-10500 -2350);
DISPLAY INVISIBLE (-10500 -2350);
FORCEADD OFFPAGE..5
(-14350 -1400);
FORCEPROP 2 LAST $XR0 151 
J 0
(-14605 -1400);
DISPLAY 0.638298 (-14605 -1400);
PAINT MONO (-14605 -1400);
FORCEPROP 2 LAST PATH I7
J 0
(-14625 -1350);
DISPLAY 1.021277 (-14625 -1350);
PAINT ORANGE (-14625 -1350);
DISPLAY INVISIBLE (-14625 -1350);
FORCEPROP 2 LAST CDS_LIB mstr_standard
J 0
(-14350 -1400);
PAINT MONO (-14350 -1400);
DISPLAY INVISIBLE (-14350 -1400);
FORCEPROP 1 LAST OFFPAGE TRUE
J 0
(-14025 -1525);
DISPLAY 0.872340 (-14025 -1525);
PAINT GREEN (-14025 -1525);
DISPLAY INVISIBLE (-14025 -1525);
FORCEPROP 1 LAST COMMENT_BODY TRUE
J 0
(-14250 -1475);
DISPLAY 0.872340 (-14250 -1475);
PAINT GREEN (-14250 -1475);
DISPLAY INVISIBLE (-14250 -1475);
FORCEADD OFFPAGE..5
(-14350 -1700);
FORCEPROP 2 LAST $XR0 151 
J 0
(-14605 -1700);
DISPLAY 0.638298 (-14605 -1700);
PAINT MONO (-14605 -1700);
FORCEPROP 2 LAST CDS_LIB mstr_standard
J 0
(-14350 -1700);
PAINT MONO (-14350 -1700);
DISPLAY INVISIBLE (-14350 -1700);
FORCEPROP 2 LAST PATH I8
J 0
(-14625 -1650);
DISPLAY 1.021277 (-14625 -1650);
PAINT ORANGE (-14625 -1650);
DISPLAY INVISIBLE (-14625 -1650);
FORCEPROP 1 LAST OFFPAGE TRUE
J 0
(-14025 -1825);
DISPLAY 0.872340 (-14025 -1825);
PAINT GREEN (-14025 -1825);
DISPLAY INVISIBLE (-14025 -1825);
FORCEPROP 1 LAST COMMENT_BODY TRUE
J 0
(-14250 -1775);
DISPLAY 0.872340 (-14250 -1775);
PAINT GREEN (-14250 -1775);
DISPLAY INVISIBLE (-14250 -1775);
FORCEADD OFFPAGE..5
(-14350 -1350);
FORCEPROP 2 LAST $XR0 151 
J 0
(-14605 -1350);
DISPLAY 0.638298 (-14605 -1350);
PAINT MONO (-14605 -1350);
FORCEPROP 2 LAST CDS_LIB mstr_standard
J 0
(-14350 -1350);
PAINT MONO (-14350 -1350);
DISPLAY INVISIBLE (-14350 -1350);
FORCEPROP 2 LAST PATH I9
J 0
(-14625 -1300);
DISPLAY 1.021277 (-14625 -1300);
PAINT ORANGE (-14625 -1300);
DISPLAY INVISIBLE (-14625 -1300);
FORCEPROP 1 LAST OFFPAGE TRUE
J 0
(-14025 -1475);
DISPLAY 0.872340 (-14025 -1475);
PAINT GREEN (-14025 -1475);
DISPLAY INVISIBLE (-14025 -1475);
FORCEPROP 1 LAST COMMENT_BODY TRUE
J 0
(-14250 -1425);
DISPLAY 0.872340 (-14250 -1425);
PAINT GREEN (-14250 -1425);
DISPLAY INVISIBLE (-14250 -1425);
FORCEADD INTEL_CORP_BPAGE..1
(-8225 -4750);
FORCEPROP 1 LAST CDS_CON_LAST_MODIFIED Fri Jun 16 17:48:54 2017
J 0
(-9650 -4425);
DISPLAY 1.361702 (-9650 -4425);
PAINT GREEN (-9650 -4425);
DISPLAY INVISIBLE (-9650 -4425);
FORCEPROP 2 LAST CUSTOM_TXT_CDS <XR_PAGE_TITLE>
J 0
(-16115 500);
DISPLAY 0.638298 (-16115 500);
PAINT PINK (-16115 500);
DISPLAY INVISIBLE (-16115 500);
FORCEPROP 2 LAST CUSTOM_TXT_CDS <CON_LAST_MODIFIED>
J 0
(-12250 -4650);
DISPLAY 1.085106 (-12250 -4650);
PAINT ORANGE (-12250 -4650);
FORCEPROP 2 LAST CUSTOM_TXT_CDS <CURRENT_DESIGN_SHEET> OF <TOTAL_DESIGN_SHEETS>
J 0
(-8725 -4725);
PAINT ORANGE (-8725 -4725);
FORCEPROP 1 LAST SCH_TITLE BMC (1 OF 7)
J 0
(-16175 -4700);
DISPLAY 1.212766 (-16175 -4700);
PAINT ORANGE (-16175 -4700);
FORCEPROP 1 LAST COMMENT_BODY TRUE
J 0
(-8213 -4738);
DISPLAY 0.617021 (-8213 -4738);
PAINT GREEN (-8213 -4738);
DISPLAY INVISIBLE (-8213 -4738);
FORCEPROP 2 LAST PAGE_BORDER TRUE
J 0
(-16115 500);
DISPLAY 0.851064 (-16115 500);
PAINT PINK (-16115 500);
DISPLAY INVISIBLE (-16115 500);
FORCEPROP 2 LAST CDS_LIB mstr_symbols
J 0
(-8225 -4750);
DISPLAY 1.361702 (-8225 -4750);
PAINT ORANGE (-8225 -4750);
DISPLAY INVISIBLE (-8225 -4750);
FORCEPROP 2 LAST CDS_XR_PAGE_TITLE CR-143 : @BASEBOARD_FAB2_LIB.BASEBOARD_FAB2(SCH_1):PAGE143
J 0
(-16115 500);
DISPLAY 0.638298 (-16115 500);
PAINT PINK (-16115 500);
DISPLAY INVISIBLE (-16115 500);
WIRE 16 -1 (-10900 -2150)(-10300 -2150);
WIRE 16 -1 (-10550 -2550)(-10550 -2600);
WIRE 16 -1 (-12125 -1500)(-11100 -1500);
FORCEPROP 2 LAST SIG_NAME BMC_M_A4
J 0
(-11935 -1490);
DISPLAY 0.680851 (-11935 -1490);
PAINT ORANGE (-11935 -1490);
WIRE 16 -1 (-14300 -1250)(-13575 -1250);
FORCEPROP 2 LAST SIG_NAME BMC_M_DQ9
J 0
(-14235 -1240);
DISPLAY 0.680851 (-14235 -1240);
PAINT ORANGE (-14235 -1240);
WIRE 16 -1 (-12125 -1700)(-11100 -1700);
FORCEPROP 2 LAST SIG_NAME BMC_M_A0
J 0
(-11935 -1690);
DISPLAY 0.680851 (-11935 -1690);
PAINT ORANGE (-11935 -1690);
WIRE 16 -1 (-14300 -1500)(-13575 -1500);
FORCEPROP 2 LAST SIG_NAME BMC_M_DQ4
J 0
(-14235 -1490);
DISPLAY 0.680851 (-14235 -1490);
PAINT ORANGE (-14235 -1490);
WIRE 16 -1 (-14300 -1350)(-13575 -1350);
FORCEPROP 2 LAST SIG_NAME BMC_M_DQ7
J 0
(-14235 -1340);
DISPLAY 0.680851 (-14235 -1340);
PAINT ORANGE (-14235 -1340);
WIRE 16 -1 (-10550 -2200)(-12125 -2200);
FORCEPROP 2 LAST SIG_NAME BMC_M_VREFCA
J 0
(-11935 -2190);
DISPLAY 0.680851 (-11935 -2190);
PAINT ORANGE (-11935 -2190);
WIRE 16 -1 (-10550 -2200)(-10550 -2350);
WIRE 16 -1 (-10300 -2200)(-10550 -2200);
WIRE 16 -1 (-12125 -1600)(-11100 -1600);
FORCEPROP 2 LAST SIG_NAME BMC_M_A2
J 0
(-11935 -1590);
DISPLAY 0.680851 (-11935 -1590);
PAINT ORANGE (-11935 -1590);
WIRE 16 -1 (-12125 -1650)(-11100 -1650);
FORCEPROP 2 LAST SIG_NAME BMC_M_A1
J 0
(-11935 -1640);
DISPLAY 0.680851 (-11935 -1640);
PAINT ORANGE (-11935 -1640);
WIRE 16 -1 (-12125 -1550)(-11100 -1550);
FORCEPROP 2 LAST SIG_NAME BMC_M_A3
J 0
(-11935 -1540);
DISPLAY 0.680851 (-11935 -1540);
PAINT ORANGE (-11935 -1540);
WIRE 16 -1 (-12125 -1250)(-11100 -1250);
FORCEPROP 2 LAST SIG_NAME BMC_M_A9
J 0
(-11935 -1240);
DISPLAY 0.680851 (-11935 -1240);
PAINT ORANGE (-11935 -1240);
WIRE 16 -1 (-12125 -1300)(-11100 -1300);
FORCEPROP 2 LAST SIG_NAME BMC_M_A8
J 0
(-11935 -1290);
DISPLAY 0.680851 (-11935 -1290);
PAINT ORANGE (-11935 -1290);
WIRE 16 -1 (-12125 -1350)(-11100 -1350);
FORCEPROP 2 LAST SIG_NAME BMC_M_A7
J 0
(-11935 -1340);
DISPLAY 0.680851 (-11935 -1340);
PAINT ORANGE (-11935 -1340);
WIRE 16 -1 (-12125 -1400)(-11100 -1400);
FORCEPROP 2 LAST SIG_NAME BMC_M_A6
J 0
(-11935 -1390);
DISPLAY 0.680851 (-11935 -1390);
PAINT ORANGE (-11935 -1390);
WIRE 16 -1 (-12125 -1450)(-11100 -1450);
FORCEPROP 2 LAST SIG_NAME BMC_M_A5
J 0
(-11935 -1440);
DISPLAY 0.680851 (-11935 -1440);
PAINT ORANGE (-11935 -1440);
WIRE 16 -1 (-12125 -950)(-11100 -950);
FORCEPROP 2 LAST SIG_NAME TP_BMC_M_A15
J 0
(-11935 -940);
DISPLAY 0.680851 (-11935 -940);
PAINT ORANGE (-11935 -940);
FORCEPROP 2 LASTPROP $XRERR UNIQUE?
J 0
(-11070 -950);
DISPLAY 0.638298 (-11070 -950);
PAINT MONO (-11070 -950);
DISPLAY INVISIBLE (-11070 -950);
WIRE 16 -1 (-12125 -1000)(-11100 -1000);
FORCEPROP 2 LAST SIG_NAME BMC_M_MACT_N
J 0
(-11935 -990);
DISPLAY 0.680851 (-11935 -990);
PAINT ORANGE (-11935 -990);
WIRE 16 -1 (-12125 -1050)(-11100 -1050);
FORCEPROP 2 LAST SIG_NAME BMC_M_A13
J 0
(-11935 -1040);
DISPLAY 0.680851 (-11935 -1040);
PAINT ORANGE (-11935 -1040);
WIRE 16 -1 (-12125 -1100)(-11100 -1100);
FORCEPROP 2 LAST SIG_NAME BMC_M_A12
J 0
(-11935 -1090);
DISPLAY 0.680851 (-11935 -1090);
PAINT ORANGE (-11935 -1090);
WIRE 16 -1 (-12125 -2000)(-11100 -2000);
FORCEPROP 2 LAST SIG_NAME BMC_M_DM1
J 0
(-11935 -1990);
DISPLAY 0.680851 (-11935 -1990);
PAINT ORANGE (-11935 -1990);
WIRE 16 -1 (-12125 -2050)(-11100 -2050);
FORCEPROP 2 LAST SIG_NAME BMC_M_DM0
J 0
(-11935 -2040);
DISPLAY 0.680851 (-11935 -2040);
PAINT ORANGE (-11935 -2040);
WIRE 16 -1 (-13575 -2000)(-14300 -2000);
FORCEPROP 2 LAST SIG_NAME BMC_M_DQS1_DN
J 0
(-14235 -1990);
DISPLAY 0.680851 (-14235 -1990);
PAINT ORANGE (-14235 -1990);
WIRE 16 -1 (-13575 -1950)(-14300 -1950);
FORCEPROP 2 LAST SIG_NAME BMC_M_DQS1_DP
J 0
(-14235 -1940);
DISPLAY 0.680851 (-14235 -1940);
PAINT ORANGE (-14235 -1940);
WIRE 16 -1 (-14300 -1600)(-13575 -1600);
FORCEPROP 2 LAST SIG_NAME BMC_M_DQ2
J 0
(-14235 -1590);
DISPLAY 0.680851 (-14235 -1590);
PAINT ORANGE (-14235 -1590);
WIRE 16 -1 (-14300 -1550)(-13575 -1550);
FORCEPROP 2 LAST SIG_NAME BMC_M_DQ3
J 0
(-14235 -1540);
DISPLAY 0.680851 (-14235 -1540);
PAINT ORANGE (-14235 -1540);
WIRE 16 -1 (-14300 -1450)(-13575 -1450);
FORCEPROP 2 LAST SIG_NAME BMC_M_DQ5
J 0
(-14235 -1440);
DISPLAY 0.680851 (-14235 -1440);
PAINT ORANGE (-14235 -1440);
WIRE 16 -1 (-14300 -1400)(-13575 -1400);
FORCEPROP 2 LAST SIG_NAME BMC_M_DQ6
J 0
(-14235 -1390);
DISPLAY 0.680851 (-14235 -1390);
PAINT ORANGE (-14235 -1390);
WIRE 16 -1 (-13575 -1850)(-14300 -1850);
FORCEPROP 2 LAST SIG_NAME BMC_M_DQS0_DN
J 0
(-14235 -1840);
DISPLAY 0.680851 (-14235 -1840);
PAINT ORANGE (-14235 -1840);
WIRE 16 -1 (-13575 -1800)(-14300 -1800);
FORCEPROP 2 LAST SIG_NAME BMC_M_DQS0_DP
J 0
(-14235 -1790);
DISPLAY 0.680851 (-14235 -1790);
PAINT ORANGE (-14235 -1790);
WIRE 16 -1 (-14300 -1700)(-13575 -1700);
FORCEPROP 2 LAST SIG_NAME BMC_M_DQ0
J 0
(-14235 -1690);
DISPLAY 0.680851 (-14235 -1690);
PAINT ORANGE (-14235 -1690);
WIRE 16 -1 (-14300 -1650)(-13575 -1650);
FORCEPROP 2 LAST SIG_NAME BMC_M_DQ1
J 0
(-14235 -1640);
DISPLAY 0.680851 (-14235 -1640);
PAINT ORANGE (-14235 -1640);
WIRE 16 -1 (-14300 -1300)(-13575 -1300);
FORCEPROP 2 LAST SIG_NAME BMC_M_DQ8
J 0
(-14235 -1290);
DISPLAY 0.680851 (-14235 -1290);
PAINT ORANGE (-14235 -1290);
WIRE 16 -1 (-14300 -1200)(-13575 -1200);
FORCEPROP 2 LAST SIG_NAME BMC_M_DQ10
J 0
(-14235 -1190);
DISPLAY 0.680851 (-14235 -1190);
PAINT ORANGE (-14235 -1190);
WIRE 16 -1 (-14300 -1150)(-13575 -1150);
FORCEPROP 2 LAST SIG_NAME BMC_M_DQ11
J 0
(-14235 -1140);
DISPLAY 0.680851 (-14235 -1140);
PAINT ORANGE (-14235 -1140);
WIRE 16 -1 (-14300 -1100)(-13575 -1100);
FORCEPROP 2 LAST SIG_NAME BMC_M_DQ12
J 0
(-14235 -1090);
DISPLAY 0.680851 (-14235 -1090);
PAINT ORANGE (-14235 -1090);
WIRE 16 -1 (-14300 -1050)(-13575 -1050);
FORCEPROP 2 LAST SIG_NAME BMC_M_DQ13
J 0
(-14235 -1040);
DISPLAY 0.680851 (-14235 -1040);
PAINT ORANGE (-14235 -1040);
WIRE 16 -1 (-14300 -1000)(-13575 -1000);
FORCEPROP 2 LAST SIG_NAME BMC_M_DQ14
J 0
(-14235 -990);
DISPLAY 0.680851 (-14235 -990);
PAINT ORANGE (-14235 -990);
WIRE 16 -1 (-13575 -950)(-14300 -950);
FORCEPROP 2 LAST SIG_NAME BMC_M_DQ15
J 0
(-14235 -940);
DISPLAY 0.680851 (-14235 -940);
PAINT ORANGE (-14235 -940);
WIRE 16 -1 (-12125 -1800)(-11100 -1800);
FORCEPROP 2 LAST SIG_NAME BMC_M_BG0
J 0
(-11935 -1790);
DISPLAY 0.680851 (-11935 -1790);
PAINT ORANGE (-11935 -1790);
WIRE 16 -1 (-11100 -2150)(-12125 -2150);
FORCEPROP 2 LAST SIG_NAME BMC_MIOZ
J 0
(-11935 -2140);
DISPLAY 0.680851 (-11935 -2140);
PAINT ORANGE (-11935 -2140);
FORCEPROP 2 LASTPROP $XRERR UNIQUE?
J 0
(-12175 -2140);
DISPLAY 0.638298 (-12175 -2140);
PAINT MONO (-12175 -2140);
DISPLAY INVISIBLE (-12175 -2140);
WIRE 16 -1 (-12125 -1900)(-11100 -1900);
FORCEPROP 2 LAST SIG_NAME BMC_M_BA0
J 0
(-11935 -1890);
DISPLAY 0.680851 (-11935 -1890);
PAINT ORANGE (-11935 -1890);
WIRE 16 -1 (-12125 -1850)(-11100 -1850);
FORCEPROP 2 LAST SIG_NAME BMC_M_BA1
J 0
(-11935 -1840);
DISPLAY 0.680851 (-11935 -1840);
PAINT ORANGE (-11935 -1840);
WIRE 16 -1 (-11100 -2750)(-12125 -2750);
FORCEPROP 2 LAST SIG_NAME BMC_M_ODT
J 0
(-11935 -2740);
DISPLAY 0.680851 (-11935 -2740);
PAINT ORANGE (-11935 -2740);
WIRE 16 -1 (-12125 -2700)(-11100 -2700);
FORCEPROP 2 LAST SIG_NAME BMC_M_CKE
J 0
(-11935 -2690);
DISPLAY 0.680851 (-11935 -2690);
PAINT ORANGE (-11935 -2690);
WIRE 16 -1 (-12125 -2600)(-11100 -2600);
FORCEPROP 2 LAST SIG_NAME BMC_M_CLK_DN
J 0
(-11935 -2590);
DISPLAY 0.680851 (-11935 -2590);
PAINT ORANGE (-11935 -2590);
WIRE 16 -1 (-12125 -2300)(-11100 -2300);
FORCEPROP 2 LAST SIG_NAME BMC_M_CS_N
J 0
(-11935 -2290);
DISPLAY 0.680851 (-11935 -2290);
PAINT ORANGE (-11935 -2290);
WIRE 16 -1 (-12125 -2550)(-11100 -2550);
FORCEPROP 2 LAST SIG_NAME BMC_M_CLK_DP
J 0
(-11935 -2540);
DISPLAY 0.680851 (-11935 -2540);
PAINT ORANGE (-11935 -2540);
WIRE 16 -1 (-12125 -2350)(-11100 -2350);
FORCEPROP 2 LAST SIG_NAME BMC_M_RAS_N
J 0
(-11935 -2340);
DISPLAY 0.680851 (-11935 -2340);
PAINT ORANGE (-11935 -2340);
WIRE 16 -1 (-12125 -2400)(-11100 -2400);
FORCEPROP 2 LAST SIG_NAME BMC_M_CAS_N
J 0
(-11935 -2390);
DISPLAY 0.680851 (-11935 -2390);
PAINT ORANGE (-11935 -2390);
WIRE 16 -1 (-12125 -2450)(-11100 -2450);
FORCEPROP 2 LAST SIG_NAME BMC_M_WE_N
J 0
(-11935 -2440);
DISPLAY 0.680851 (-11935 -2440);
PAINT ORANGE (-11935 -2440);
WIRE 16 -1 (-12125 -1200)(-11100 -1200);
FORCEPROP 2 LAST SIG_NAME BMC_M_A10
J 0
(-11935 -1190);
DISPLAY 0.680851 (-11935 -1190);
PAINT ORANGE (-11935 -1190);
WIRE 16 -1 (-12125 -1150)(-11100 -1150);
FORCEPROP 2 LAST SIG_NAME BMC_M_A11
J 0
(-11935 -1140);
DISPLAY 0.680851 (-11935 -1140);
PAINT ORANGE (-11935 -1140);
DOT 1 (-10550 -2200);
FORCENOTE
ROOM=BMC
(-16125 -4450) 0;
DISPLAY LEFT (-16125 -4450);
DISPLAY 1.595745 (-16125 -4450);
PAINT PURPLE (-16125 -4450);
FORCENOTE
BOM_COST=SM_CONTROLLER
(-16125 -4550) 0;
DISPLAY LEFT (-16125 -4550);
DISPLAY 1.595745 (-16125 -4550);
PAINT PURPLE (-16125 -4550);
QUIT
